# S9S_MB_2U (Grand Teton) — schematic netlist excerpt (pin names and nets, part order shuffled) for the footprints in the layout excerpt that follows; sources: Cadence DE-HDL packaged netlist, KiCad conversion of 03242023_DA0F0TMBIJ0_F0T_Motherboard_J_brd_V01_OCP.brd

C272  Q_CAP  22UF 4V 20% X6S  pkg C0402  page 77 : A = PVCCIN_CPU1 ; B = GND
R3292  Q_RES  4.7K 1% CHIP  pkg 0402LF  page 166 : A = P3V3_AUX ; B = CLK_GEN2_GPU_FPGA_OE_OR_N

(kicad_pcb
	(version 20260206)
	(generator "pcbnew")
	(generator_version "10.0")
	(general
		(thickness 1.6)
		(legacy_teardrops no)
	)
	(paper "A4")
	(title_block
		(title "03242023_DA0F0TMBIJ0_F0T_Motherboard_J_brd_V01_OCP.brd")
		(comment 1 "Grand Teton / footprints 3908-3909 of 6105")
	)
	(layers
		(0 "F.Cu" signal "TOP")
		(4 "In1.Cu" signal "GND")
		(6 "In2.Cu" signal "IN1")
		(8 "In3.Cu" signal "GND1")
		(10 "In4.Cu" signal "IN2")
		(12 "In5.Cu" signal "GND2")
		(14 "In6.Cu" signal "IN3")
		(16 "In7.Cu" signal "GND3")
		(18 "In8.Cu" signal "VCC")
		(20 "In9.Cu" signal "VCC1")
		(22 "In10.Cu" signal "GND4")
		(24 "In11.Cu" signal "IN4")
		(26 "In12.Cu" signal "GND5")
		(28 "In13.Cu" signal "IN5")
		(30 "In14.Cu" signal "GND6")
		(32 "In15.Cu" signal "IN6")
		(34 "In16.Cu" signal "GND7")
		(2 "B.Cu" signal "BOTTOM")
		(9 "F.Adhes" user "F.Adhesive")
		(11 "B.Adhes" user "B.Adhesive")
		(13 "F.Paste" user "Package Geometry/Pastemask Top")
		(15 "B.Paste" user "Package Geometry/Pastemask Bottom")
		(5 "F.SilkS" user "Ref Des/Silkscreen Top")
		(7 "B.SilkS" user "Ref Des/Silkscreen Bottom")
		(1 "F.Mask" user "Board Geometry/Soldermask Top")
		(3 "B.Mask" user "Board Geometry/Soldermask Bottom")
		(17 "Dwgs.User" user "User.Drawings")
		(19 "Cmts.User" user "User.Comments")
		(21 "Eco1.User" user "User.Eco1")
		(23 "Eco2.User" user "User.Eco2")
		(25 "Edge.Cuts" user "Board Geometry/Outline")
		(27 "Margin" user)
		(31 "F.CrtYd" user "Package Geometry/Place Bound Top")
		(29 "B.CrtYd" user "Package Geometry/Place Bound Bottom")
		(35 "F.Fab" user "Ref Des/Assembly Top")
		(33 "B.Fab" user "Ref Des/Assembly Bottom")
	)
	(footprint ""
		(layer "F.Cu")
		(at 27.628596 -388.262876 180)
		(property "Reference" "R3292"
			(at 0 0 180)
			(layer "F.SilkS")
			(hide yes)
			(effects
				(font
					(size 1.27 1.27)
				)
			)
		)
		(property "Value" ""
			(at 0 0 180)
			(layer "F.Fab")
			(effects
				(font
					(size 1.27 1.27)
				)
			)
		)
		(duplicate_pad_numbers_are_jumpers no)
		(fp_line
			(start 0.7874 0.4064)
			(end -0.7874 0.4064)
			(stroke
				(width 0.1524)
				(type default)
			)
			(layer "F.SilkS")
		)
		(fp_line
			(start 0.7874 -0.4064)
			(end 0.7874 0.4064)
			(stroke
				(width 0.1524)
				(type default)
			)
			(layer "F.SilkS")
		)
		(fp_line
			(start -0.7874 0.4064)
			(end -0.7874 -0.4064)
			(stroke
				(width 0.1524)
				(type default)
			)
			(layer "F.SilkS")
		)
		(fp_line
			(start -0.7874 -0.4064)
			(end 0.7874 -0.4064)
			(stroke
				(width 0.1524)
				(type default)
			)
			(layer "F.SilkS")
		)
		(fp_line
			(start 0.67945 0.3048)
			(end 0.120396 0.3048)
			(stroke
				(width 0.1)
				(type default)
			)
			(layer "F.Fab")
		)
		(fp_line
			(start 0.67945 -0.3048)
			(end 0.67945 0.3048)
			(stroke
				(width 0.1)
				(type default)
			)
			(layer "F.Fab")
		)
		(fp_line
			(start 0.12065 -0.2794)
			(end 0.12065 -0.3048)
			(stroke
				(width 0.1)
				(type default)
			)
			(layer "F.Fab")
		)
		(fp_line
			(start 0.12065 -0.3048)
			(end 0.67945 -0.3048)
			(stroke
				(width 0.1)
				(type default)
			)
			(layer "F.Fab")
		)
		(fp_line
			(start 0.120396 0.3048)
			(end 0.120396 0.2794)
			(stroke
				(width 0.1)
				(type default)
			)
			(layer "F.Fab")
		)
		(fp_line
			(start 0.120396 0.2794)
			(end -0.12065 0.2794)
			(stroke
				(width 0.1)
				(type default)
			)
			(layer "F.Fab")
		)
		(fp_line
			(start -0.12065 0.3048)
			(end -0.67945 0.3048)
			(stroke
				(width 0.1)
				(type default)
			)
			(layer "F.Fab")
		)
		(fp_line
			(start -0.12065 0.2794)
			(end -0.12065 0.3048)
			(stroke
				(width 0.1)
				(type default)
			)
			(layer "F.Fab")
		)
		(fp_line
			(start -0.12065 -0.2794)
			(end 0.12065 -0.2794)
			(stroke
				(width 0.1)
				(type default)
			)
			(layer "F.Fab")
		)
		(fp_line
			(start -0.12065 -0.305054)
			(end -0.12065 -0.2794)
			(stroke
				(width 0.1)
				(type default)
			)
			(layer "F.Fab")
		)
		(fp_line
			(start -0.67945 0.3048)
			(end -0.67945 -0.305054)
			(stroke
				(width 0.1)
				(type default)
			)
			(layer "F.Fab")
		)
		(fp_line
			(start -0.67945 -0.305054)
			(end -0.12065 -0.305054)
			(stroke
				(width 0.1)
				(type default)
			)
			(layer "F.Fab")
		)
		(pad "1" smd circle
			(at -0.40005 0 180)
			(size 0 0)
			(layers "F.Cu" "F.Mask" "F.Paste")
			(net "P3V3_AUX")
		)
		(pad "2" smd circle
			(at 0.40005 0 180)
			(size 0 0)
			(layers "F.Cu" "F.Mask" "F.Paste")
			(net "CLK_GEN2_GPU_FPGA_OE_OR_N")
		)
	)
	(footprint ""
		(layer "F.Cu")
		(at 107.296204 -245.634256 -90)
		(property "Reference" "C272"
			(at 0 0 270)
			(layer "F.SilkS")
			(hide yes)
			(effects
				(font
					(size 1.27 1.27)
				)
			)
		)
		(property "Value" ""
			(at 0 0 270)
			(layer "F.Fab")
			(effects
				(font
					(size 1.27 1.27)
				)
			)
		)
		(duplicate_pad_numbers_are_jumpers no)
		(fp_line
			(start -0.7874 0.4064)
			(end -0.7874 -0.4064)
			(stroke
				(width 0.1524)
				(type default)
			)
			(layer "F.SilkS")
		)
		(fp_line
			(start 0.7874 0.4064)
			(end -0.7874 0.4064)
			(stroke
				(width 0.1524)
				(type default)
			)
			(layer "F.SilkS")
		)
		(fp_line
			(start -0.7874 -0.4064)
			(end 0.7874 -0.4064)
			(stroke
				(width 0.1524)
				(type default)
			)
			(layer "F.SilkS")
		)
		(fp_line
			(start 0.7874 -0.4064)
			(end 0.7874 0.4064)
			(stroke
				(width 0.1524)
				(type default)
			)
			(layer "F.SilkS")
		)
		(fp_line
			(start -0.67945 0.3048)
			(end -0.67945 -0.305054)
			(stroke
				(width 0.1)
				(type default)
			)
			(layer "F.Fab")
		)
		(fp_line
			(start -0.12065 0.3048)
			(end -0.67945 0.3048)
			(stroke
				(width 0.1)
				(type default)
			)
			(layer "F.Fab")
		)
		(fp_line
			(start 0.120396 0.3048)
			(end 0.120396 0.2794)
			(stroke
				(width 0.1)
				(type default)
			)
			(layer "F.Fab")
		)
		(fp_line
			(start 0.67945 0.3048)
			(end 0.120396 0.3048)
			(stroke
				(width 0.1)
				(type default)
			)
			(layer "F.Fab")
		)
		(fp_line
			(start -0.12065 0.2794)
			(end -0.12065 0.3048)
			(stroke
				(width 0.1)
				(type default)
			)
			(layer "F.Fab")
		)
		(fp_line
			(start 0.120396 0.2794)
			(end -0.12065 0.2794)
			(stroke
				(width 0.1)
				(type default)
			)
			(layer "F.Fab")
		)
		(fp_line
			(start -0.12065 -0.2794)
			(end 0.12065 -0.2794)
			(stroke
				(width 0.1)
				(type default)
			)
			(layer "F.Fab")
		)
		(fp_line
			(start 0.12065 -0.2794)
			(end 0.12065 -0.3048)
			(stroke
				(width 0.1)
				(type default)
			)
			(layer "F.Fab")
		)
		(fp_line
			(start 0.12065 -0.3048)
			(end 0.67945 -0.3048)
			(stroke
				(width 0.1)
				(type default)
			)
			(layer "F.Fab")
		)
		(fp_line
			(start 0.67945 -0.3048)
			(end 0.67945 0.3048)
			(stroke
				(width 0.1)
				(type default)
			)
			(layer "F.Fab")
		)
		(fp_line
			(start -0.67945 -0.305054)
			(end -0.12065 -0.305054)
			(stroke
				(width 0.1)
				(type default)
			)
			(layer "F.Fab")
		)
		(fp_line
			(start -0.12065 -0.305054)
			(end -0.12065 -0.2794)
			(stroke
				(width 0.1)
				(type default)
			)
			(layer "F.Fab")
		)
		(pad "1" smd circle
			(at -0.40005 0 270)
			(size 0 0)
			(layers "F.Cu" "F.Mask" "F.Paste")
			(net "PVCCIN_CPU1")
		)
		(pad "2" smd circle
			(at 0.40005 0 270)
			(size 0 0)
			(layers "F.Cu" "F.Mask" "F.Paste")
			(net "GND")
		)
	)
)
